# T6G (Grand Teton) — schematic netlist excerpt (pin names and nets, part order shuffled) for the footprints in the layout excerpt that follows; sources: Cadence DE-HDL packaged netlist, KiCad conversion of 04192023_DAF0TMB3IC0_F0TG_MB_C_brd_V02_OCP.brd

J24  SCONN288_DDR506112002KQ  IO  pkg DDR288S_1-1VXC  page 98
  VIN_BULK0  = P12V_MEM_CPU1
  RFU0  = NC
  VIN_MGMT  = P3V3_AUX
  HSCL  = I3C_SPD_DDRA_CPU1_SCL
  HSDA  = I3C_SPD_DDRA_CPU1_SDA
  VSS0  = GND
  DQ0_A  = M_A_CPU1_SA_DQ<0>
  VSS1  = GND
  DQ1_A  = M_A_CPU1_SA_DQ<1>
  VSS2  = GND
  DQS0_A_T  = M_A_CPU1_SA_DQS_DP<0>
  DQS0_A_C  = M_A_CPU1_SA_DQS_DN<0>
  VSS3  = GND
  DQ4_A  = M_A_CPU1_SA_DQ<4>
  VSS4  = GND
  DQ5_A  = M_A_CPU1_SA_DQ<5>
  VSS5  = GND
  DQ8_A  = M_A_CPU1_SA_DQ<8>
  VSS6  = GND
  DQ9_A  = M_A_CPU1_SA_DQ<9>
  VSS7  = GND
  DQS1_A_T  = M_A_CPU1_SA_DQS_DP<1>
  DQS1_A_C  = M_A_CPU1_SA_DQS_DN<1>
  VSS8  = GND
  DQ12_A  = M_A_CPU1_SA_DQ<12>
  VSS9  = GND
  DQ13_A  = M_A_CPU1_SA_DQ<13>
  VSS10  = GND
  DQ16_A  = M_A_CPU1_SA_DQ<16>
  VSS11  = GND
  DQ17_A  = M_A_CPU1_SA_DQ<17>
  VSS12  = GND
  DQS2_A_T  = M_A_CPU1_SA_DQS_DP<2>
  DQS2_A_C  = M_A_CPU1_SA_DQS_DN<2>
  VSS13  = GND
  DQ20_A  = M_A_CPU1_SA_DQ<20>
  VSS14  = GND
  DQ21_A  = M_A_CPU1_SA_DQ<21>
  VSS15  = GND
  DQ24_A  = M_A_CPU1_SA_DQ<24>
  VSS16  = GND
  DQ25_A  = M_A_CPU1_SA_DQ<25>
  VSS17  = GND
  DQS3_A_T  = M_A_CPU1_SA_DQS_DP<3>
  DQS3_A_C  = M_A_CPU1_SA_DQS_DN<3>
  VSS18  = GND
  DQ28_A  = M_A_CPU1_SA_DQ<28>
  VSS19  = GND
  DQ29_A  = M_A_CPU1_SA_DQ<29>
  VSS20  = GND
  CB0_A  = M_A_CPU1_SA_CB<0>
  VSS21  = GND
  CB1_A  = M_A_CPU1_SA_CB<1>
  VSS22  = GND
  DQS4_A_T  = M_A_CPU1_SA_DQS_DP<4>
  DQS4_A_C  = M_A_CPU1_SA_DQS_DN<4>
  VSS23  = GND
  CB4_A  = M_A_CPU1_SA_CB<4>
  VSS24  = GND
  CB5_A  = M_A_CPU1_SA_CB<5>
  VSS25  = GND
  ALERT_N  = M_A_CPU1_ALERT_N
  VSS26  = GND
  CS0_A_N  = M_A_CPU1_SA_CS_N<0>
  VSS27  = GND
  CA0_A  = M_A_CPU1_SA_CA<0>
  VSS28  = GND
  CA2_A  = M_A_CPU1_SA_CA<2>
  VSS29  = GND
  CA4_A  = M_A_CPU1_SA_CA<4>
  VSS30  = GND
  CA6_A  = M_A_CPU1_SA_CA<6>
  VSS31  = GND
  PAR_A  = M_A_CPU1_SA_PAR
  VSS32  = GND
  CA0_B  = M_A_CPU1_SB_CA<0>
  VSS33  = GND
  CA2_B  = M_A_CPU1_SB_CA<2>
  VSS34  = GND
  CA4_B  = M_A_CPU1_SB_CA<4>
  VSS35  = GND
  CA6_B  = M_A_CPU1_SB_CA<6>
  VSS36  = GND
  CS0_B_N  = M_A_CPU1_SB_CS_N<0>
  VSS37  = GND
  \lbd||rsp_a_n\  = M_A_CPU1_SA_RSP<0>
  \lbs||rsp_b_n\  = M_A_CPU1_SB_RSP<0>
  VSS38  = GND
  CB4_B  = M_A_CPU1_SB_CB<4>
  VSS39  = GND
  CB5_B  = M_A_CPU1_SB_CB<5>
  VSS40  = GND
  \dqs9_b_t||tdqs9_b_t||dbi4_b_n\  = M_A_CPU1_SB_DQS_DP<9>
  \dqs9_b_c||tdqs9_b_c\  = M_A_CPU1_SB_DQS_DN<9>
  VSS41  = GND
  CB0_B  = M_A_CPU1_SB_CB<0>
  VSS42  = GND
  CB1_B  = M_A_CPU1_SB_CB<1>
  VSS43  = GND
  DQ0_B  = M_A_CPU1_SB_DQ<0>
  VSS44  = GND
  DQ1_B  = M_A_CPU1_SB_DQ<1>
  VSS45  = GND
  DQS0_B_T  = M_A_CPU1_SB_DQS_DP<0>
  DQS0_B_C  = M_A_CPU1_SB_DQS_DN<0>
  VSS46  = GND
  DQ4_B  = M_A_CPU1_SB_DQ<4>
  VSS47  = GND
  DQ5_B  = M_A_CPU1_SB_DQ<5>
  VSS48  = GND
  DQ8_B  = M_A_CPU1_SB_DQ<8>
  VSS49  = GND
  DQ9_B  = M_A_CPU1_SB_DQ<9>
  VSS50  = GND
  DQS1_B_T  = M_A_CPU1_SB_DQS_DP<1>
  DQS1_B_C  = M_A_CPU1_SB_DQS_DN<1>
  VSS51  = GND
  DQ12_B  = M_A_CPU1_SB_DQ<12>
  VSS52  = GND
  DQ13_B  = M_A_CPU1_SB_DQ<13>
  VSS53  = GND
  DQ16_B  = M_A_CPU1_SB_DQ<16>
  VSS54  = GND
  DQ17_B  = M_A_CPU1_SB_DQ<17>
  VSS55  = GND
  DQS2_B_T  = M_A_CPU1_SB_DQS_DP<2>
  DQS2_B_C  = M_A_CPU1_SB_DQS_DN<2>
  VSS56  = GND
  DQ20_B  = M_A_CPU1_SB_DQ<20>
  VSS57  = GND
  DQ21_B  = M_A_CPU1_SB_DQ<21>
  VSS58  = GND
  DQ24_B  = M_A_CPU1_SB_DQ<24>
  VSS59  = GND
  DQ25_B  = M_A_CPU1_SB_DQ<25>
  VSS60  = GND
  DQS3_B_T  = M_A_CPU1_SB_DQS_DP<3>
  DQS3_B_C  = M_A_CPU1_SB_DQS_DN<3>
  VSS61  = GND
  DQ28_B  = M_A_CPU1_SB_DQ<28>
  VSS62  = GND
  DQ29_B  = M_A_CPU1_SB_DQ<29>
  VSS63  = GND
  RFU1  = NC
  VIN_BULK1  = P12V_MEM_CPU1
  VIN_BULK2  = P12V_MEM_CPU1
  \pwr_good||fail_n\  = PWRGD_CHA_CPU1_DIMM0
  HAS  = PD_CHA_CPU1_DIMM0_SAA
  RFU2  = NC
  RFU3  = NC
  VSS64  = GND
  DQ2_A  = M_A_CPU1_SA_DQ<2>
  VSS65  = GND
  DQ3_A  = M_A_CPU1_SA_DQ<3>
  VSS66  = GND
  \dqs5_a_c||tdqs5_a_c||dqs5_a_t||tdqs5_a_t\  = M_A_CPU1_SA_DQS_DN<5>
  \dqs5_a_t||tdqs5_a_t\  = M_A_CPU1_SA_DQS_DP<5>
  VSS67  = GND
  DQ6_A  = M_A_CPU1_SA_DQ<6>
  VSS68  = GND
  DQ7_A  = M_A_CPU1_SA_DQ<7>
  VSS69  = GND
  DQ10_A  = M_A_CPU1_SA_DQ<10>
  VSS70  = GND
  DQ11_A  = M_A_CPU1_SA_DQ<11>
  VSS71  = GND
  \dqs6_a_c||tdqs6_a_c||dqs6_a_t||tdqs6_a_t\  = M_A_CPU1_SA_DQS_DN<6>
  \dqs6_a_t||tdqs6_a_t\  = M_A_CPU1_SA_DQS_DP<6>
  VSS72  = GND
  DQ14_A  = M_A_CPU1_SA_DQ<14>
  VSS73  = GND
  DQ15_A  = M_A_CPU1_SA_DQ<15>
  VSS74  = GND
  DQ18_A  = M_A_CPU1_SA_DQ<18>
  VSS75  = GND
  DQ19_A  = M_A_CPU1_SA_DQ<19>
  VSS76  = GND
  \dqs7_a_c||tdqs7_a_c\  = M_A_CPU1_SA_DQS_DN<7>
  \dqs7_a_t||tdqs7_a_t\  = M_A_CPU1_SA_DQS_DP<7>
  VSS77  = GND
  DQ22_A  = M_A_CPU1_SA_DQ<22>
  VSS78  = GND
  DQ23_A  = M_A_CPU1_SA_DQ<23>
  VSS79  = GND
  DQ26_A  = M_A_CPU1_SA_DQ<26>
  VSS80  = GND
  DQ27_A  = M_A_CPU1_SA_DQ<27>
  VSS81  = GND
  \dqs8_a_c||tdqs8_a_c\  = M_A_CPU1_SA_DQS_DN<8>
  \dqs8_a_t||tdqs8_a_t\  = M_A_CPU1_SA_DQS_DP<8>
  VSS82  = GND
  DQ30_A  = M_A_CPU1_SA_DQ<30>
  VSS83  = GND
  DQ31_A  = M_A_CPU1_SA_DQ<31>
  VSS84  = GND
  CB2_A  = M_A_CPU1_SA_CB<2>
  VSS85  = GND
  CB3_A  = M_A_CPU1_SA_CB<3>
  VSS86  = GND
  \dqs9_a_c||tdqs9_a_c\  = M_A_CPU1_SA_DQS_DN<9>
  \dqs9_a_t||tdqs9_a_t\  = M_A_CPU1_SA_DQS_DP<9>
  VSS87  = GND
  CB6_A  = M_A_CPU1_SA_CB<6>
  VSS88  = GND
  CB7_A  = M_A_CPU1_SA_CB<7>
  VSS89  = GND
  RESET_N  = M_A_CPU1_RESET_N
  VSS90  = GND
  CS1_A_N  = M_A_CPU1_SA_CS_N<1>
  VSS91  = GND
  CA1_A  = M_A_CPU1_SA_CA<1>
  VSS92  = GND
  CA3_A  = M_A_CPU1_SA_CA<3>
  VSS93  = GND
  CA5_A  = M_A_CPU1_SA_CA<5>
  VSS94  = GND
  CK_T  = M_A_CPU1_CLK_DP<0>
  CK_C  = M_A_CPU1_CLK_DN<0>
  VSS95  = GND
  RFU4  = NC
  CA1_B  = M_A_CPU1_SB_CA<1>
  VSS96  = GND
  CA3_B  = M_A_CPU1_SB_CA<3>
  VSS97  = GND
  CA5_B  = M_A_CPU1_SB_CA<5>
  VSS98  = GND
  PAR_B  = M_A_CPU1_SB_PAR
  VSS99  = GND
  CS1_B_N  = M_A_CPU1_SB_CS_N<1>
  VSS100  = GND
  RFU5  = NC
  RFU6  = NC
  VSS101  = GND
  CB6_B  = M_A_CPU1_SB_CB<6>
  VSS102  = GND
  CB7_B  = M_A_CPU1_SB_CB<7>
  VSS103  = GND
  DQS4_B_C  = M_A_CPU1_SB_DQS_DN<4>
  DQS4_B_T  = M_A_CPU1_SB_DQS_DP<4>
  VSS104  = GND
  CB2_B  = M_A_CPU1_SB_CB<2>
  VSS105  = GND
  CB3_B  = M_A_CPU1_SB_CB<3>
  VSS106  = GND
  DQ2_B  = M_A_CPU1_SB_DQ<2>
  VSS107  = GND
  DQ3_B  = M_A_CPU1_SB_DQ<3>
  VSS108  = GND
  \dqs5_b_c||tdqs5_b_c\  = M_A_CPU1_SB_DQS_DN<5>
  \dqs5_b_t||tdqs5_b_t\  = M_A_CPU1_SB_DQS_DP<5>
  VSS109  = GND
  DQ6_B  = M_A_CPU1_SB_DQ<6>
  VSS110  = GND
  DQ7_B  = M_A_CPU1_SB_DQ<7>
  VSS111  = GND
  DQ10_B  = M_A_CPU1_SB_DQ<10>
  VSS112  = GND
  DQ11_B  = M_A_CPU1_SB_DQ<11>
  VSS113  = GND
  \dqs6_b_c||tdqs6_b_c\  = M_A_CPU1_SB_DQS_DN<6>
  \dqs6_b_t||tdqs6_b_t\  = M_A_CPU1_SB_DQS_DP<6>
  VSS114  = GND
  DQ14_B  = M_A_CPU1_SB_DQ<14>
  VSS115  = GND
  DQ15_B  = M_A_CPU1_SB_DQ<15>
  VSS116  = GND
  DQ18_B  = M_A_CPU1_SB_DQ<18>
  VSS117  = GND
  DQ19_B  = M_A_CPU1_SB_DQ<19>
  VSS118  = GND
  \dqs7_b_c||tdqs7_b_c\  = M_A_CPU1_SB_DQS_DN<7>
  \dqs7_b_t||tdqs7_b_t\  = M_A_CPU1_SB_DQS_DP<7>
  VSS119  = GND
  DQ22_B  = M_A_CPU1_SB_DQ<22>
  VSS120  = GND
  DQ23_B  = M_A_CPU1_SB_DQ<23>
  VSS121  = GND
  DQ26_B  = M_A_CPU1_SB_DQ<26>
  VSS122  = GND
  DQ27_B  = M_A_CPU1_SB_DQ<27>
  VSS123  = GND
  \dqs8_b_c||tdqs8_b_c\  = M_A_CPU1_SB_DQS_DN<8>
  \dqs8_b_t||tdqs8_b_t\  = M_A_CPU1_SB_DQS_DP<8>
  VSS124  = GND
  DQ30_B  = M_A_CPU1_SB_DQ<30>
  VSS125  = GND
  DQ31_B  = M_A_CPU1_SB_DQ<31>
  VSS126  = GND
  G1  = GND
  G2  = GND
  G3  = GND

(kicad_pcb
	(version 20260206)
	(generator "pcbnew")
	(generator_version "10.0")
	(general
		(thickness 1.6)
		(legacy_teardrops no)
	)
	(paper "A4")
	(title_block
		(title "04192023_DAF0TMB3IC0_F0TG_MB_C_brd_V02_OCP.brd")
		(comment 1 "Grand Teton / footprint 2100 of 8354 (J24), pads 277-291 of 291")
	)
	(layers
		(0 "F.Cu" signal "TOP")
		(4 "In1.Cu" signal "GND")
		(6 "In2.Cu" signal "IN1")
		(8 "In3.Cu" signal "GND1")
		(10 "In4.Cu" signal "IN2")
		(12 "In5.Cu" signal "GND2")
		(14 "In6.Cu" signal "IN3")
		(16 "In7.Cu" signal "GND3")
		(18 "In8.Cu" signal "VCC")
		(20 "In9.Cu" signal "VCC1")
		(22 "In10.Cu" signal "GND4")
		(24 "In11.Cu" signal "IN4")
		(26 "In12.Cu" signal "GND5")
		(28 "In13.Cu" signal "IN5")
		(30 "In14.Cu" signal "GND6")
		(32 "In15.Cu" signal "IN6")
		(34 "In16.Cu" signal "GND7")
		(2 "B.Cu" signal "BOTTOM")
		(9 "F.Adhes" user "F.Adhesive")
		(11 "B.Adhes" user "B.Adhesive")
		(13 "F.Paste" user "Package Geometry/Pastemask Top")
		(15 "B.Paste" user "Package Geometry/Pastemask Bottom")
		(5 "F.SilkS" user "Ref Des/Silkscreen Top")
		(7 "B.SilkS" user "Ref Des/Silkscreen Bottom")
		(1 "F.Mask" user "Board Geometry/Soldermask Top")
		(3 "B.Mask" user "Board Geometry/Soldermask Bottom")
		(17 "Dwgs.User" user "User.Drawings")
		(19 "Cmts.User" user "User.Comments")
		(21 "Eco1.User" user "User.Eco1")
		(23 "Eco2.User" user "User.Eco2")
		(25 "Edge.Cuts" user "Board Geometry/Outline")
		(27 "Margin" user)
		(31 "F.CrtYd" user "Package Geometry/Place Bound Top")
		(29 "B.CrtYd" user "Package Geometry/Place Bound Bottom")
		(35 "F.Fab" user "Ref Des/Assembly Top")
		(33 "B.Fab" user "Ref Des/Assembly Bottom")
	)
	(footprint ""
		(layer "F.Cu")
		(at 57.378092 -255.560322 180)
		(property "Reference" "J24"
			(at 1.914906 -84.58708 0)
			(unlocked yes)
			(layer "F.SilkS")
			(effects
				(font
					(size 0.7874 0.5842)
					(thickness 0.1524)
				)
			)
		)
		(property "Value" ""
			(at 0 0 180)
			(layer "F.Fab")
			(effects
				(font
					(size 1.27 1.27)
				)
			)
		)
		(duplicate_pad_numbers_are_jumpers no)
		(pad "277" smd rect
			(at 2.050034 53.975 90)
			(size 0.519938 1.4986)
			(layers "F.Cu" "F.Mask" "F.Paste")
			(net "GND")
		)
		(pad "278" smd rect
			(at 2.050034 54.824884 90)
			(size 0.519938 1.4986)
			(layers "F.Cu" "F.Mask" "F.Paste")
			(net "M_A_CPU1_SB_DQ<26>")
		)
		(pad "279" smd rect
			(at 2.050034 55.675022 90)
			(size 0.519938 1.4986)
			(layers "F.Cu" "F.Mask" "F.Paste")
			(net "GND")
		)
		(pad "280" smd rect
			(at 2.050034 56.524906 90)
			(size 0.519938 1.4986)
			(layers "F.Cu" "F.Mask" "F.Paste")
			(net "M_A_CPU1_SB_DQ<27>")
		)
		(pad "281" smd rect
			(at 2.050034 57.375044 90)
			(size 0.519938 1.4986)
			(layers "F.Cu" "F.Mask" "F.Paste")
			(net "GND")
		)
		(pad "282" smd rect
			(at 2.050034 58.224928 90)
			(size 0.519938 1.4986)
			(layers "F.Cu" "F.Mask" "F.Paste")
			(net "M_A_CPU1_SB_DQS_DN<8>")
		)
		(pad "283" smd rect
			(at 2.050034 59.075066 90)
			(size 0.519938 1.4986)
			(layers "F.Cu" "F.Mask" "F.Paste")
			(net "M_A_CPU1_SB_DQS_DP<8>")
		)
		(pad "284" smd rect
			(at 2.050034 59.92495 90)
			(size 0.519938 1.4986)
			(layers "F.Cu" "F.Mask" "F.Paste")
			(net "GND")
		)
		(pad "285" smd rect
			(at 2.050034 60.775088 90)
			(size 0.519938 1.4986)
			(layers "F.Cu" "F.Mask" "F.Paste")
			(net "M_A_CPU1_SB_DQ<30>")
		)
		(pad "286" smd rect
			(at 2.050034 61.624972 90)
			(size 0.519938 1.4986)
			(layers "F.Cu" "F.Mask" "F.Paste")
			(net "GND")
		)
		(pad "287" smd rect
			(at 2.050034 62.47511 90)
			(size 0.519938 1.4986)
			(layers "F.Cu" "F.Mask" "F.Paste")
			(net "M_A_CPU1_SB_DQ<31>")
		)
		(pad "288" smd rect
			(at 2.050034 63.324994 90)
			(size 0.519938 1.4986)
			(layers "F.Cu" "F.Mask" "F.Paste")
			(net "GND")
		)
		(pad "G1" thru_hole oval
			(at 0 -68.97497 90)
			(size 1.7272 3.4798)
			(drill oval 1.2192 2.4638)
			(layers "*.Cu" "*.Mask")
			(remove_unused_layers no)
			(net "GND")
			(clearance 0.127)
			(thermal_gap 0.127)
		)
		(pad "G2" thru_hole oval
			(at 0 3.875024 90)
			(size 1.7272 3.4798)
			(drill oval 1.2192 2.4638)
			(layers "*.Cu" "*.Mask")
			(remove_unused_layers no)
			(net "GND")
			(clearance 0.127)
			(thermal_gap 0.127)
		)
		(pad "G3" thru_hole oval
			(at 0 68.97497 90)
			(size 1.7272 3.4798)
			(drill oval 1.2192 2.4638)
			(layers "*.Cu" "*.Mask")
			(remove_unused_layers no)
			(net "GND")
			(clearance 0.127)
			(thermal_gap 0.127)
		)
	)
)
